(kicad_pcb
	(version 20260206)
	(generator "pcbnew")
	(generator_version "10.0")
	(general
		(thickness 1.6)
		(legacy_teardrops no)
	)
	(paper "A4")
	(title_block
		(title "Bryce Canyon_R.DPB_16317-1_OCP.brd")
		(comment 1 "Bryce Canyon / footprints 1893-1899 of 2099")
	)
	(layers
		(0 "F.Cu" signal "TOP")
		(4 "In1.Cu" signal "L2GND")
		(6 "In2.Cu" signal "L3")
		(8 "In3.Cu" signal "L4VCC")
		(10 "In4.Cu" signal "L5VCC")
		(12 "In5.Cu" signal "L6")
		(14 "In6.Cu" signal "L7GND")
		(2 "B.Cu" signal "BOTTOM")
		(9 "F.Adhes" user "F.Adhesive")
		(11 "B.Adhes" user "B.Adhesive")
		(13 "F.Paste" user "Package Geometry/Pastemask Top")
		(15 "B.Paste" user "Package Geometry/Pastemask Bottom")
		(5 "F.SilkS" user "Ref Des/Silkscreen Top")
		(7 "B.SilkS" user "Ref Des/Silkscreen Bottom")
		(1 "F.Mask" user "Board Geometry/Soldermask Top")
		(3 "B.Mask" user "Board Geometry/Soldermask Bottom")
		(17 "Dwgs.User" user "User.Drawings")
		(19 "Cmts.User" user "User.Comments")
		(21 "Eco1.User" user "User.Eco1")
		(23 "Eco2.User" user "User.Eco2")
		(25 "Edge.Cuts" user "Board Geometry/Outline")
		(27 "Margin" user)
		(31 "F.CrtYd" user "Package Geometry/Place Bound Top")
		(29 "B.CrtYd" user "Package Geometry/Place Bound Bottom")
		(35 "F.Fab" user "Ref Des/Assembly Top")
		(33 "B.Fab" user "Ref Des/Assembly Bottom")
	)
	(footprint ""
		(layer "F.Cu")
		(at 332.105 -243.586)
		(property "Reference" "R263"
			(at 0 0 0)
			(layer "F.SilkS")
			(hide yes)
			(effects
				(font
					(size 1.27 1.27)
				)
			)
		)
		(property "Value" "4K7R2F-GP"
			(at 0.064008 -3.993896 0)
			(unlocked yes)
			(layer "F.Fab")
			(hide yes)
			(effects
				(font
					(size 1.016 1.016)
					(thickness 0.1524)
				)
			)
		)
		(property "Device Type" "R402H16"
			(at 0.064008 -5.517896 0)
			(unlocked yes)
			(layer "F.Fab")
			(hide yes)
			(effects
				(font
					(size 1.016 1.016)
					(thickness 0.1524)
				)
			)
		)
		(duplicate_pad_numbers_are_jumpers no)
		(fp_line
			(start -0.508 -0.9398)
			(end -0.508 0.9398)
			(stroke
				(width 0.1524)
				(type default)
			)
			(layer "F.SilkS")
		)
		(fp_line
			(start 0.508 -0.9398)
			(end -0.508 -0.9398)
			(stroke
				(width 0.1524)
				(type default)
			)
			(layer "F.SilkS")
		)
		(fp_rect
			(start -0.508 0.9398)
			(end 0.508 -0.9398)
			(stroke
				(width 0)
				(type default)
			)
			(fill no)
			(layer "F.CrtYd")
		)
		(fp_rect
			(start -0.508 0.9398)
			(end 0.508 -0.9398)
			(stroke
				(width 0)
				(type default)
			)
			(fill no)
			(layer "F.Fab")
		)
		(pad "1" smd custom
			(at 0 -0.4445)
			(size 0.1397 0.1397)
			(layers "F.Cu" "F.Mask" "F.Paste")
			(net "SW_PWR_R_HDD6")
			(options
				(clearance outline)
				(anchor circle)
			)
			(primitives
				(gr_poly
					(pts
						(arc
							(start -0.1778 -0.2794)
							(mid -0.249642 -0.249642)
							(end -0.2794 -0.1778)
						)
						(arc
							(start -0.2794 0.1778)
							(mid -0.249642 0.249642)
							(end -0.1778 0.2794)
						)
						(arc
							(start 0.1778 0.2794)
							(mid 0.249642 0.249642)
							(end 0.2794 0.1778)
						)
						(arc
							(start 0.2794 -0.1778)
							(mid 0.249642 -0.249642)
							(end 0.1778 -0.2794)
						)
					)
					(width 0)
					(fill yes)
				)
			)
		)
		(pad "2" smd custom
			(at 0 0.4445)
			(size 0.1397 0.1397)
			(layers "F.Cu" "F.Mask" "F.Paste")
			(net "GND")
			(options
				(clearance outline)
				(anchor circle)
			)
			(primitives
				(gr_poly
					(pts
						(arc
							(start -0.1778 -0.2794)
							(mid -0.249642 -0.249642)
							(end -0.2794 -0.1778)
						)
						(arc
							(start -0.2794 0.1778)
							(mid -0.249642 0.249642)
							(end -0.1778 0.2794)
						)
						(arc
							(start 0.1778 0.2794)
							(mid 0.249642 0.249642)
							(end 0.2794 0.1778)
						)
						(arc
							(start 0.2794 -0.1778)
							(mid 0.249642 -0.249642)
							(end 0.1778 -0.2794)
						)
					)
					(width 0)
					(fill yes)
				)
			)
		)
	)
	(footprint ""
		(layer "F.Cu")
		(at 383.8956 -31.6484 180)
		(property "Reference" "R806"
			(at 0 0 180)
			(layer "F.SilkS")
			(hide yes)
			(effects
				(font
					(size 1.27 1.27)
				)
			)
		)
		(property "Value" "10KR2F-2-GP"
			(at 0.064008 -3.993896 180)
			(unlocked yes)
			(layer "F.Fab")
			(hide yes)
			(effects
				(font
					(size 1.016 1.016)
					(thickness 0.1524)
				)
			)
		)
		(property "Device Type" "R402H16"
			(at 0.064008 -5.517896 180)
			(unlocked yes)
			(layer "F.Fab")
			(hide yes)
			(effects
				(font
					(size 1.016 1.016)
					(thickness 0.1524)
				)
			)
		)
		(duplicate_pad_numbers_are_jumpers no)
		(fp_line
			(start 0.508 -0.9398)
			(end -0.508 -0.9398)
			(stroke
				(width 0.1524)
				(type default)
			)
			(layer "F.SilkS")
		)
		(fp_line
			(start -0.508 -0.9398)
			(end -0.508 0.9398)
			(stroke
				(width 0.1524)
				(type default)
			)
			(layer "F.SilkS")
		)
		(fp_rect
			(start -0.508 0.9398)
			(end 0.508 -0.9398)
			(stroke
				(width 0)
				(type default)
			)
			(fill no)
			(layer "F.CrtYd")
		)
		(fp_rect
			(start -0.508 0.9398)
			(end 0.508 -0.9398)
			(stroke
				(width 0)
				(type default)
			)
			(fill no)
			(layer "F.Fab")
		)
		(pad "1" smd custom
			(at 0 -0.4445 180)
			(size 0.1397 0.1397)
			(layers "F.Cu" "F.Mask" "F.Paste")
			(net "P3V3_STBY_B")
			(options
				(clearance outline)
				(anchor circle)
			)
			(primitives
				(gr_poly
					(pts
						(arc
							(start -0.1778 -0.2794)
							(mid -0.249642 -0.249642)
							(end -0.2794 -0.1778)
						)
						(arc
							(start -0.2794 0.1778)
							(mid -0.249642 0.249642)
							(end -0.1778 0.2794)
						)
						(arc
							(start 0.1778 0.2794)
							(mid 0.249642 0.249642)
							(end 0.2794 0.1778)
						)
						(arc
							(start 0.2794 -0.1778)
							(mid 0.249642 -0.249642)
							(end 0.1778 -0.2794)
						)
					)
					(width 0)
					(fill yes)
				)
			)
		)
		(pad "2" smd custom
			(at 0 0.4445 180)
			(size 0.1397 0.1397)
			(layers "F.Cu" "F.Mask" "F.Paste")
			(net "HDD_PRSNT_32")
			(options
				(clearance outline)
				(anchor circle)
			)
			(primitives
				(gr_poly
					(pts
						(arc
							(start -0.1778 -0.2794)
							(mid -0.249642 -0.249642)
							(end -0.2794 -0.1778)
						)
						(arc
							(start -0.2794 0.1778)
							(mid -0.249642 0.249642)
							(end -0.1778 0.2794)
						)
						(arc
							(start 0.1778 0.2794)
							(mid 0.249642 0.249642)
							(end 0.2794 0.1778)
						)
						(arc
							(start 0.2794 -0.1778)
							(mid 0.249642 -0.249642)
							(end 0.1778 -0.2794)
						)
					)
					(width 0)
					(fill yes)
				)
			)
		)
	)
	(footprint ""
		(layer "F.Cu")
		(at 109.347 -35.687 -90)
		(property "Reference" "C385"
			(at 0 0 270)
			(layer "F.SilkS")
			(hide yes)
			(effects
				(font
					(size 1.27 1.27)
				)
			)
		)
		(property "Value" "SC4D7U25V5KX-1-GP"
			(at -0.0762 -6.1214 270)
			(unlocked yes)
			(layer "F.Fab")
			(hide yes)
			(effects
				(font
					(size 1.016 1.016)
					(thickness 0.1524)
				)
			)
		)
		(property "Device Type" "C805H58"
			(at -0.0762 -8.1534 270)
			(unlocked yes)
			(layer "F.Fab")
			(hide yes)
			(effects
				(font
					(size 1.016 1.016)
					(thickness 0.1524)
				)
			)
		)
		(duplicate_pad_numbers_are_jumpers no)
		(fp_line
			(start 0.635 0)
			(end -0.635 0)
			(stroke
				(width 0.508)
				(type default)
			)
			(layer "F.SilkS")
		)
		(fp_rect
			(start -0.9652 1.778)
			(end 0.9652 -1.778)
			(stroke
				(width 0)
				(type default)
			)
			(fill no)
			(layer "F.CrtYd")
		)
		(fp_poly
			(pts
				(xy -0.9652 -1.778) (xy 0.9652 -1.778) (xy 0.9652 1.778) (xy -0.9652 1.778)
			)
			(stroke
				(width 0)
				(type default)
			)
			(fill no)
			(layer "F.Fab")
		)
		(pad "1" smd rect
			(at 0 -0.9652 270)
			(size 1.397 1.143)
			(layers "F.Cu" "F.Mask" "F.Paste")
			(net "P12V_HDD27")
		)
		(pad "2" smd rect
			(at 0 0.9652 270)
			(size 1.397 1.143)
			(layers "F.Cu" "F.Mask" "F.Paste")
			(net "GND")
		)
	)
	(footprint ""
		(layer "F.Cu")
		(at 384.734562 -130.21945 -90)
		(property "Reference" "C288"
			(at 0 0 270)
			(layer "F.SilkS")
			(hide yes)
			(effects
				(font
					(size 1.27 1.27)
				)
			)
		)
		(property "Value" "SCD01U16V1KX-GP"
			(at -2.8321 -1.7399 270)
			(unlocked yes)
			(layer "F.Fab")
			(hide yes)
			(effects
				(font
					(size 1.016 1.016)
					(thickness 0.1524)
				)
			)
		)
		(property "Device Type" "C0201H13"
			(at -2.8321 -3.2639 270)
			(unlocked yes)
			(layer "F.Fab")
			(hide yes)
			(effects
				(font
					(size 1.016 1.016)
					(thickness 0.1524)
				)
			)
		)
		(duplicate_pad_numbers_are_jumpers no)
		(fp_rect
			(start -0.2794 0.6477)
			(end 0.2794 -0.6477)
			(stroke
				(width 0)
				(type default)
			)
			(fill no)
			(layer "F.CrtYd")
		)
		(fp_rect
			(start -0.2794 0.6477)
			(end 0.2794 -0.6477)
			(stroke
				(width 0)
				(type default)
			)
			(fill no)
			(layer "F.Fab")
		)
		(pad "1" smd custom
			(at 0 -0.2794 270)
			(size 0.0762 0.0762)
			(layers "F.Cu" "F.Mask" "F.Paste")
			(net "SAS_HDD_RX_N20")
			(options
				(clearance outline)
				(anchor circle)
			)
			(primitives
				(gr_poly
					(pts
						(arc
							(start 0.1524 -0.127)
							(mid 0.137521 -0.162921)
							(end 0.1016 -0.1778)
						)
						(arc
							(start -0.1016 -0.1778)
							(mid -0.137521 -0.162921)
							(end -0.1524 -0.127)
						)
						(arc
							(start -0.1524 0.127)
							(mid -0.137521 0.162921)
							(end -0.1016 0.1778)
						)
						(arc
							(start 0.1016 0.1778)
							(mid 0.137521 0.162921)
							(end 0.1524 0.127)
						)
					)
					(width 0)
					(fill yes)
				)
			)
		)
		(pad "2" smd custom
			(at 0 0.2794 270)
			(size 0.0762 0.0762)
			(layers "F.Cu" "F.Mask" "F.Paste")
			(net "PHY_SCC_B_TO_DRV_B_20_DN")
			(options
				(clearance outline)
				(anchor circle)
			)
			(primitives
				(gr_poly
					(pts
						(arc
							(start 0.1524 -0.127)
							(mid 0.137521 -0.162921)
							(end 0.1016 -0.1778)
						)
						(arc
							(start -0.1016 -0.1778)
							(mid -0.137521 -0.162921)
							(end -0.1524 -0.127)
						)
						(arc
							(start -0.1524 0.127)
							(mid -0.137521 0.162921)
							(end -0.1016 0.1778)
						)
						(arc
							(start 0.1016 0.1778)
							(mid 0.137521 0.162921)
							(end 0.1524 0.127)
						)
					)
					(width 0)
					(fill yes)
				)
			)
		)
	)
	(footprint ""
		(layer "F.Cu")
		(at 129.921 -147.066 90)
		(property "Reference" "C232"
			(at 0 0 90)
			(layer "F.SilkS")
			(hide yes)
			(effects
				(font
					(size 1.27 1.27)
				)
			)
		)
		(property "Value" "SCD01U50V2KX-1GP"
			(at 1.1811 -2.7051 90)
			(unlocked yes)
			(layer "F.Fab")
			(hide yes)
			(effects
				(font
					(size 1.016 1.016)
					(thickness 0.1524)
				)
			)
		)
		(property "Device Type" "C402H22"
			(at 1.1811 -4.2291 90)
			(unlocked yes)
			(layer "F.Fab")
			(hide yes)
			(effects
				(font
					(size 1.016 1.016)
					(thickness 0.1524)
				)
			)
		)
		(duplicate_pad_numbers_are_jumpers no)
		(fp_rect
			(start -0.4318 0.9525)
			(end 0.4318 -0.9525)
			(stroke
				(width 0)
				(type default)
			)
			(fill no)
			(layer "F.CrtYd")
		)
		(fp_rect
			(start -0.4318 0.9525)
			(end 0.4318 -0.9525)
			(stroke
				(width 0)
				(type default)
			)
			(fill no)
			(layer "F.Fab")
		)
		(pad "1" smd custom
			(at 0 -0.4445 90)
			(size 0.1524 0.1524)
			(layers "F.Cu" "F.Mask" "F.Paste")
			(net "HDD_PRSNT_15")
			(options
				(clearance outline)
				(anchor circle)
			)
			(primitives
				(gr_poly
					(pts
						(arc
							(start 0.3048 -0.2032)
							(mid 0.275042 -0.275042)
							(end 0.2032 -0.3048)
						)
						(arc
							(start -0.2032 -0.3048)
							(mid -0.275042 -0.275042)
							(end -0.3048 -0.2032)
						)
						(arc
							(start -0.3048 0.2032)
							(mid -0.275042 0.275042)
							(end -0.2032 0.3048)
						)
						(arc
							(start 0.2032 0.3048)
							(mid 0.275042 0.275042)
							(end 0.3048 0.2032)
						)
					)
					(width 0)
					(fill yes)
				)
			)
		)
		(pad "2" smd custom
			(at 0 0.4445 90)
			(size 0.1524 0.1524)
			(layers "F.Cu" "F.Mask" "F.Paste")
			(net "GND")
			(options
				(clearance outline)
				(anchor circle)
			)
			(primitives
				(gr_poly
					(pts
						(arc
							(start 0.3048 -0.2032)
							(mid 0.275042 -0.275042)
							(end 0.2032 -0.3048)
						)
						(arc
							(start -0.2032 -0.3048)
							(mid -0.275042 -0.275042)
							(end -0.3048 -0.2032)
						)
						(arc
							(start -0.3048 0.2032)
							(mid -0.275042 0.275042)
							(end -0.2032 0.3048)
						)
						(arc
							(start 0.2032 0.3048)
							(mid 0.275042 0.275042)
							(end 0.3048 0.2032)
						)
					)
					(width 0)
					(fill yes)
				)
			)
		)
	)
	(footprint ""
		(layer "F.Cu")
		(at 178.099974 -377.219972 180)
		(property "Reference" "FLED2"
			(at 0 0 180)
			(layer "F.SilkS")
			(hide yes)
			(effects
				(font
					(size 1.27 1.27)
				)
			)
		)
		(property "Value" "LED-BY-14-GP"
			(at -4.7752 -2.1844 180)
			(unlocked yes)
			(layer "F.Fab")
			(hide yes)
			(effects
				(font
					(size 1.016 1.016)
					(thickness 0.1524)
				)
			)
		)
		(property "Device Type" "LED-100-3PH206"
			(at -4.7752 -3.7084 180)
			(unlocked yes)
			(layer "F.Fab")
			(hide yes)
			(effects
				(font
					(size 1.016 1.016)
					(thickness 0.1524)
				)
			)
		)
		(duplicate_pad_numbers_are_jumpers no)
		(fp_line
			(start 3.7592 8.0264)
			(end -3.7592 8.0264)
			(stroke
				(width 0.1524)
				(type default)
			)
			(layer "F.SilkS")
		)
		(fp_line
			(start 3.7592 -1.524)
			(end 3.7592 8.0264)
			(stroke
				(width 0.1524)
				(type default)
			)
			(layer "F.SilkS")
		)
		(fp_line
			(start 1.87833 3.63474)
			(end 0.58293 2.33934)
			(stroke
				(width 0.1524)
				(type default)
			)
			(layer "F.SilkS")
		)
		(fp_line
			(start 1.87833 2.33934)
			(end 2.81813 2.33934)
			(stroke
				(width 0.1524)
				(type default)
			)
			(layer "F.SilkS")
		)
		(fp_line
			(start 1.87833 1.04394)
			(end 1.87833 3.63474)
			(stroke
				(width 0.1524)
				(type default)
			)
			(layer "F.SilkS")
		)
		(fp_line
			(start 0.58293 3.05054)
			(end 0.58293 1.42494)
			(stroke
				(width 0.1524)
				(type default)
			)
			(layer "F.SilkS")
		)
		(fp_line
			(start 0.58293 2.33934)
			(end 1.87833 1.04394)
			(stroke
				(width 0.1524)
				(type default)
			)
			(layer "F.SilkS")
		)
		(fp_line
			(start -0.45847 3.05054)
			(end -0.45847 1.42494)
			(stroke
				(width 0.1524)
				(type default)
			)
			(layer "F.SilkS")
		)
		(fp_line
			(start -0.45847 2.33934)
			(end 0.58293 2.33934)
			(stroke
				(width 0.1524)
				(type default)
			)
			(layer "F.SilkS")
		)
		(fp_line
			(start -0.45847 2.33934)
			(end -1.75387 1.04394)
			(stroke
				(width 0.1524)
				(type default)
			)
			(layer "F.SilkS")
		)
		(fp_line
			(start -1.75387 3.63474)
			(end -0.45847 2.33934)
			(stroke
				(width 0.1524)
				(type default)
			)
			(layer "F.SilkS")
		)
		(fp_line
			(start -1.75387 2.33934)
			(end -3.45567 2.33934)
			(stroke
				(width 0.1524)
				(type default)
			)
			(layer "F.SilkS")
		)
		(fp_line
			(start -1.75387 1.04394)
			(end -1.75387 3.63474)
			(stroke
				(width 0.1524)
				(type default)
			)
			(layer "F.SilkS")
		)
		(fp_line
			(start -3.7592 8.0264)
			(end -3.7592 -1.524)
			(stroke
				(width 0.1524)
				(type default)
			)
			(layer "F.SilkS")
		)
		(fp_line
			(start -3.7592 -1.524)
			(end 3.7592 -1.524)
			(stroke
				(width 0.1524)
				(type default)
			)
			(layer "F.SilkS")
		)
		(fp_circle
			(center 2.54 0)
			(end 1.5494 0)
			(stroke
				(width 0.3048)
				(type default)
			)
			(fill no)
			(layer "F.SilkS")
		)
		(fp_circle
			(center 0 0)
			(end -0.9906 0)
			(stroke
				(width 0.3048)
				(type default)
			)
			(fill no)
			(layer "F.SilkS")
		)
		(fp_circle
			(center -2.54 0)
			(end -3.5306 0)
			(stroke
				(width 0.3048)
				(type default)
			)
			(fill no)
			(layer "F.SilkS")
		)
		(fp_rect
			(start -3.5052 7.7724)
			(end 3.5052 -1.27)
			(stroke
				(width 0)
				(type default)
			)
			(fill no)
			(layer "F.CrtYd")
		)
		(fp_poly
			(pts
				(xy -4.0132 8.2804) (xy -4.0132 -1.778) (xy -3.5052 -1.778) (xy -3.5052 7.7724) (xy 3.5052 7.7724)
				(xy 3.5052 -1.27) (xy -3.50012 -1.27) (xy -3.50012 -1.778) (xy 4.0132 -1.778) (xy 4.0132 8.2804)
			)
			(stroke
				(width 0)
				(type default)
			)
			(fill no)
			(layer "F.CrtYd")
		)
		(fp_rect
			(start -4.0132 8.2804)
			(end 4.0132 -1.778)
			(stroke
				(width 0)
				(type default)
			)
			(fill no)
			(layer "F.Fab")
		)
		(pad "1" thru_hole circle
			(at -2.54 0 180)
			(size 1.27 1.27)
			(drill 0.889)
			(layers "*.Cu" "*.Mask")
			(remove_unused_layers no)
			(net "FAN_LED_BLUE1")
			(clearance 0.1651)
			(thermal_gap 0.1651)
		)
		(pad "2" thru_hole circle
			(at 0 0 180)
			(size 1.27 1.27)
			(drill 0.889)
			(layers "*.Cu" "*.Mask")
			(remove_unused_layers no)
			(net "GND")
			(clearance 0.1651)
			(thermal_gap 0.1651)
		)
		(pad "3" thru_hole circle
			(at 2.54 0 180)
			(size 1.27 1.27)
			(drill 0.889)
			(layers "*.Cu" "*.Mask")
			(remove_unused_layers no)
			(net "FAN_LED_YELLOW_1")
			(clearance 0.1651)
			(thermal_gap 0.1651)
		)
	)
	(footprint ""
		(layer "F.Cu")
		(at 321.634612 -15.219426 -90)
		(property "Reference" "C418"
			(at 0 0 270)
			(layer "F.SilkS")
			(hide yes)
			(effects
				(font
					(size 1.27 1.27)
				)
			)
		)
		(property "Value" "SCD01U16V1KX-GP"
			(at -2.8321 -1.7399 270)
			(unlocked yes)
			(layer "F.Fab")
			(hide yes)
			(effects
				(font
					(size 1.016 1.016)
					(thickness 0.1524)
				)
			)
		)
		(property "Device Type" "C0201H13"
			(at -2.8321 -3.2639 270)
			(unlocked yes)
			(layer "F.Fab")
			(hide yes)
			(effects
				(font
					(size 1.016 1.016)
					(thickness 0.1524)
				)
			)
		)
		(duplicate_pad_numbers_are_jumpers no)
		(fp_rect
			(start -0.2794 0.6477)
			(end 0.2794 -0.6477)
			(stroke
				(width 0)
				(type default)
			)
			(fill no)
			(layer "F.CrtYd")
		)
		(fp_rect
			(start -0.2794 0.6477)
			(end 0.2794 -0.6477)
			(stroke
				(width 0)
				(type default)
			)
			(fill no)
			(layer "F.Fab")
		)
		(pad "1" smd custom
			(at 0 -0.2794 270)
			(size 0.0762 0.0762)
			(layers "F.Cu" "F.Mask" "F.Paste")
			(net "SAS_HDD_RX_N30")
			(options
				(clearance outline)
				(anchor circle)
			)
			(primitives
				(gr_poly
					(pts
						(arc
							(start 0.1524 -0.127)
							(mid 0.137521 -0.162921)
							(end 0.1016 -0.1778)
						)
						(arc
							(start -0.1016 -0.1778)
							(mid -0.137521 -0.162921)
							(end -0.1524 -0.127)
						)
						(arc
							(start -0.1524 0.127)
							(mid -0.137521 0.162921)
							(end -0.1016 0.1778)
						)
						(arc
							(start 0.1016 0.1778)
							(mid 0.137521 0.162921)
							(end 0.1524 0.127)
						)
					)
					(width 0)
					(fill yes)
				)
			)
		)
		(pad "2" smd custom
			(at 0 0.2794 270)
			(size 0.0762 0.0762)
			(layers "F.Cu" "F.Mask" "F.Paste")
			(net "PHY_SCC_B_TO_DRV_B_30_DN")
			(options
				(clearance outline)
				(anchor circle)
			)
			(primitives
				(gr_poly
					(pts
						(arc
							(start 0.1524 -0.127)
							(mid 0.137521 -0.162921)
							(end 0.1016 -0.1778)
						)
						(arc
							(start -0.1016 -0.1778)
							(mid -0.137521 -0.162921)
							(end -0.1524 -0.127)
						)
						(arc
							(start -0.1524 0.127)
							(mid -0.137521 0.162921)
							(end -0.1016 0.1778)
						)
						(arc
							(start 0.1016 0.1778)
							(mid 0.137521 0.162921)
							(end 0.1524 0.127)
						)
					)
					(width 0)
					(fill yes)
				)
			)
		)
	)
)
